(kicad_pcb
	(version 20260206)
	(generator "pcbnew")
	(generator_version "10.0")
	(general
		(thickness 1.6)
		(legacy_teardrops no)
	)
	(paper "A4")
	(title_block
		(title "12092022_DA0F0TMDCD0_F0T_Management_Board_D_brd_V3_OCP.brd")
		(comment 1 "Grand Teton / footprints 980-985 of 1440")
	)
	(layers
		(0 "F.Cu" signal "TOP")
		(4 "In1.Cu" signal "GND")
		(6 "In2.Cu" signal "IN1")
		(8 "In3.Cu" signal "GND1")
		(10 "In4.Cu" signal "IN2")
		(12 "In5.Cu" signal "VCC")
		(14 "In6.Cu" signal "VCC1")
		(16 "In7.Cu" signal "IN3")
		(18 "In8.Cu" signal "GND2")
		(20 "In9.Cu" signal "IN4")
		(22 "In10.Cu" signal "GND3")
		(2 "B.Cu" signal "BOTTOM")
		(9 "F.Adhes" user "F.Adhesive")
		(11 "B.Adhes" user "B.Adhesive")
		(13 "F.Paste" user "Package Geometry/Pastemask Top")
		(15 "B.Paste" user "Package Geometry/Pastemask Bottom")
		(5 "F.SilkS" user "Ref Des/Silkscreen Top")
		(7 "B.SilkS" user "Ref Des/Silkscreen Bottom")
		(1 "F.Mask" user "Board Geometry/Soldermask Top")
		(3 "B.Mask" user "Board Geometry/Soldermask Bottom")
		(17 "Dwgs.User" user "User.Drawings")
		(19 "Cmts.User" user "User.Comments")
		(21 "Eco1.User" user "User.Eco1")
		(23 "Eco2.User" user "User.Eco2")
		(25 "Edge.Cuts" user "Board Geometry/Outline")
		(27 "Margin" user)
		(31 "F.CrtYd" user "Package Geometry/Place Bound Top")
		(29 "B.CrtYd" user "Package Geometry/Place Bound Bottom")
		(35 "F.Fab" user "Ref Des/Assembly Top")
		(33 "B.Fab" user "Ref Des/Assembly Bottom")
	)
	(footprint ""
		(layer "B.Cu")
		(at 80.772 -33.4645 -90)
		(property "Reference" "R403"
			(at 0 0 90)
			(layer "B.SilkS")
			(hide yes)
			(effects
				(font
					(size 1.27 1.27)
				)
				(justify mirror)
			)
		)
		(property "Value" ""
			(at 0 0 90)
			(layer "B.Fab")
			(effects
				(font
					(size 1.27 1.27)
				)
				(justify mirror)
			)
		)
		(duplicate_pad_numbers_are_jumpers no)
		(fp_line
			(start -0.7874 0.4064)
			(end 0.7874 0.4064)
			(stroke
				(width 0.1524)
				(type default)
			)
			(layer "B.SilkS")
		)
		(fp_line
			(start 0.7874 0.4064)
			(end 0.7874 -0.4064)
			(stroke
				(width 0.1524)
				(type default)
			)
			(layer "B.SilkS")
		)
		(fp_line
			(start -0.7874 -0.4064)
			(end -0.7874 0.4064)
			(stroke
				(width 0.1524)
				(type default)
			)
			(layer "B.SilkS")
		)
		(fp_line
			(start 0.7874 -0.4064)
			(end -0.7874 -0.4064)
			(stroke
				(width 0.1524)
				(type default)
			)
			(layer "B.SilkS")
		)
		(fp_line
			(start -0.67945 0.3048)
			(end -0.120396 0.3048)
			(stroke
				(width 0.1)
				(type default)
			)
			(layer "B.Fab")
		)
		(fp_line
			(start -0.120396 0.3048)
			(end -0.120396 0.2794)
			(stroke
				(width 0.1)
				(type default)
			)
			(layer "B.Fab")
		)
		(fp_line
			(start 0.12065 0.3048)
			(end 0.67945 0.3048)
			(stroke
				(width 0.1)
				(type default)
			)
			(layer "B.Fab")
		)
		(fp_line
			(start 0.67945 0.3048)
			(end 0.67945 -0.305054)
			(stroke
				(width 0.1)
				(type default)
			)
			(layer "B.Fab")
		)
		(fp_line
			(start -0.120396 0.2794)
			(end 0.12065 0.2794)
			(stroke
				(width 0.1)
				(type default)
			)
			(layer "B.Fab")
		)
		(fp_line
			(start 0.12065 0.2794)
			(end 0.12065 0.3048)
			(stroke
				(width 0.1)
				(type default)
			)
			(layer "B.Fab")
		)
		(fp_line
			(start -0.12065 -0.2794)
			(end -0.12065 -0.3048)
			(stroke
				(width 0.1)
				(type default)
			)
			(layer "B.Fab")
		)
		(fp_line
			(start 0.12065 -0.2794)
			(end -0.12065 -0.2794)
			(stroke
				(width 0.1)
				(type default)
			)
			(layer "B.Fab")
		)
		(fp_line
			(start -0.67945 -0.3048)
			(end -0.67945 0.3048)
			(stroke
				(width 0.1)
				(type default)
			)
			(layer "B.Fab")
		)
		(fp_line
			(start -0.12065 -0.3048)
			(end -0.67945 -0.3048)
			(stroke
				(width 0.1)
				(type default)
			)
			(layer "B.Fab")
		)
		(fp_line
			(start 0.12065 -0.305054)
			(end 0.12065 -0.2794)
			(stroke
				(width 0.1)
				(type default)
			)
			(layer "B.Fab")
		)
		(fp_line
			(start 0.67945 -0.305054)
			(end 0.12065 -0.305054)
			(stroke
				(width 0.1)
				(type default)
			)
			(layer "B.Fab")
		)
		(pad "1" smd circle
			(at 0.40005 0 90)
			(size 0 0)
			(layers "B.Cu" "B.Mask" "B.Paste")
			(net "P3V3_AUX")
		)
		(pad "2" smd circle
			(at -0.40005 0 90)
			(size 0 0)
			(layers "B.Cu" "B.Mask" "B.Paste")
			(net "PWRGD_P2V5_AUX_R")
		)
	)
	(footprint ""
		(layer "B.Cu")
		(at 35.8902 -19.9898 180)
		(property "Reference" "C211"
			(at 0 0 0)
			(layer "B.SilkS")
			(hide yes)
			(effects
				(font
					(size 1.27 1.27)
				)
				(justify mirror)
			)
		)
		(property "Value" ""
			(at 0 0 0)
			(layer "B.Fab")
			(effects
				(font
					(size 1.27 1.27)
				)
				(justify mirror)
			)
		)
		(duplicate_pad_numbers_are_jumpers no)
		(fp_line
			(start 0.7874 0.4064)
			(end 0.7874 -0.4064)
			(stroke
				(width 0.1524)
				(type default)
			)
			(layer "B.SilkS")
		)
		(fp_line
			(start 0.7874 -0.4064)
			(end -0.7874 -0.4064)
			(stroke
				(width 0.1524)
				(type default)
			)
			(layer "B.SilkS")
		)
		(fp_line
			(start -0.7874 0.4064)
			(end 0.7874 0.4064)
			(stroke
				(width 0.1524)
				(type default)
			)
			(layer "B.SilkS")
		)
		(fp_line
			(start -0.7874 -0.4064)
			(end -0.7874 0.4064)
			(stroke
				(width 0.1524)
				(type default)
			)
			(layer "B.SilkS")
		)
		(fp_line
			(start 0.67945 0.3048)
			(end 0.67945 -0.305054)
			(stroke
				(width 0.1)
				(type default)
			)
			(layer "B.Fab")
		)
		(fp_line
			(start 0.67945 -0.305054)
			(end 0.12065 -0.305054)
			(stroke
				(width 0.1)
				(type default)
			)
			(layer "B.Fab")
		)
		(fp_line
			(start 0.12065 0.3048)
			(end 0.67945 0.3048)
			(stroke
				(width 0.1)
				(type default)
			)
			(layer "B.Fab")
		)
		(fp_line
			(start 0.12065 0.2794)
			(end 0.12065 0.3048)
			(stroke
				(width 0.1)
				(type default)
			)
			(layer "B.Fab")
		)
		(fp_line
			(start 0.12065 -0.2794)
			(end -0.12065 -0.2794)
			(stroke
				(width 0.1)
				(type default)
			)
			(layer "B.Fab")
		)
		(fp_line
			(start 0.12065 -0.305054)
			(end 0.12065 -0.2794)
			(stroke
				(width 0.1)
				(type default)
			)
			(layer "B.Fab")
		)
		(fp_line
			(start -0.120396 0.3048)
			(end -0.120396 0.2794)
			(stroke
				(width 0.1)
				(type default)
			)
			(layer "B.Fab")
		)
		(fp_line
			(start -0.120396 0.2794)
			(end 0.12065 0.2794)
			(stroke
				(width 0.1)
				(type default)
			)
			(layer "B.Fab")
		)
		(fp_line
			(start -0.12065 -0.2794)
			(end -0.12065 -0.3048)
			(stroke
				(width 0.1)
				(type default)
			)
			(layer "B.Fab")
		)
		(fp_line
			(start -0.12065 -0.3048)
			(end -0.67945 -0.3048)
			(stroke
				(width 0.1)
				(type default)
			)
			(layer "B.Fab")
		)
		(fp_line
			(start -0.67945 0.3048)
			(end -0.120396 0.3048)
			(stroke
				(width 0.1)
				(type default)
			)
			(layer "B.Fab")
		)
		(fp_line
			(start -0.67945 -0.3048)
			(end -0.67945 0.3048)
			(stroke
				(width 0.1)
				(type default)
			)
			(layer "B.Fab")
		)
		(pad "1" smd circle
			(at 0.40005 0)
			(size 0 0)
			(layers "B.Cu" "B.Mask" "B.Paste")
			(net "V_VGAHS_BUF")
		)
		(pad "2" smd circle
			(at -0.40005 0)
			(size 0 0)
			(layers "B.Cu" "B.Mask" "B.Paste")
			(net "GND")
		)
	)
	(footprint ""
		(layer "B.Cu")
		(at 47.4218 -76.2762)
		(property "Reference" "R111"
			(at 0 0 0)
			(layer "B.SilkS")
			(hide yes)
			(effects
				(font
					(size 1.27 1.27)
				)
				(justify mirror)
			)
		)
		(property "Value" ""
			(at 0 0 0)
			(layer "B.Fab")
			(effects
				(font
					(size 1.27 1.27)
				)
				(justify mirror)
			)
		)
		(duplicate_pad_numbers_are_jumpers no)
		(fp_line
			(start -0.7874 -0.4064)
			(end -0.7874 0.4064)
			(stroke
				(width 0.1524)
				(type default)
			)
			(layer "B.SilkS")
		)
		(fp_line
			(start -0.7874 0.4064)
			(end 0.7874 0.4064)
			(stroke
				(width 0.1524)
				(type default)
			)
			(layer "B.SilkS")
		)
		(fp_line
			(start 0.7874 -0.4064)
			(end -0.7874 -0.4064)
			(stroke
				(width 0.1524)
				(type default)
			)
			(layer "B.SilkS")
		)
		(fp_line
			(start 0.7874 0.4064)
			(end 0.7874 -0.4064)
			(stroke
				(width 0.1524)
				(type default)
			)
			(layer "B.SilkS")
		)
		(fp_line
			(start -0.67945 -0.3048)
			(end -0.67945 0.3048)
			(stroke
				(width 0.1)
				(type default)
			)
			(layer "B.Fab")
		)
		(fp_line
			(start -0.67945 0.3048)
			(end -0.120396 0.3048)
			(stroke
				(width 0.1)
				(type default)
			)
			(layer "B.Fab")
		)
		(fp_line
			(start -0.12065 -0.3048)
			(end -0.67945 -0.3048)
			(stroke
				(width 0.1)
				(type default)
			)
			(layer "B.Fab")
		)
		(fp_line
			(start -0.12065 -0.2794)
			(end -0.12065 -0.3048)
			(stroke
				(width 0.1)
				(type default)
			)
			(layer "B.Fab")
		)
		(fp_line
			(start -0.120396 0.2794)
			(end 0.12065 0.2794)
			(stroke
				(width 0.1)
				(type default)
			)
			(layer "B.Fab")
		)
		(fp_line
			(start -0.120396 0.3048)
			(end -0.120396 0.2794)
			(stroke
				(width 0.1)
				(type default)
			)
			(layer "B.Fab")
		)
		(fp_line
			(start 0.12065 -0.305054)
			(end 0.12065 -0.2794)
			(stroke
				(width 0.1)
				(type default)
			)
			(layer "B.Fab")
		)
		(fp_line
			(start 0.12065 -0.2794)
			(end -0.12065 -0.2794)
			(stroke
				(width 0.1)
				(type default)
			)
			(layer "B.Fab")
		)
		(fp_line
			(start 0.12065 0.2794)
			(end 0.12065 0.3048)
			(stroke
				(width 0.1)
				(type default)
			)
			(layer "B.Fab")
		)
		(fp_line
			(start 0.12065 0.3048)
			(end 0.67945 0.3048)
			(stroke
				(width 0.1)
				(type default)
			)
			(layer "B.Fab")
		)
		(fp_line
			(start 0.67945 -0.305054)
			(end 0.12065 -0.305054)
			(stroke
				(width 0.1)
				(type default)
			)
			(layer "B.Fab")
		)
		(fp_line
			(start 0.67945 0.3048)
			(end 0.67945 -0.305054)
			(stroke
				(width 0.1)
				(type default)
			)
			(layer "B.Fab")
		)
		(pad "1" smd circle
			(at 0.40005 0 180)
			(size 0 0)
			(layers "B.Cu" "B.Mask" "B.Paste")
			(net "FM_BMC_READY_R_PLD_N")
		)
		(pad "2" smd circle
			(at -0.40005 0 180)
			(size 0 0)
			(layers "B.Cu" "B.Mask" "B.Paste")
			(net "FM_BMC_READY_PLD_N")
		)
	)
	(footprint ""
		(layer "B.Cu")
		(at 24.202644 -95.130112 180)
		(property "Reference" "C263"
			(at 0 0 0)
			(layer "B.SilkS")
			(hide yes)
			(effects
				(font
					(size 1.27 1.27)
				)
				(justify mirror)
			)
		)
		(property "Value" ""
			(at 0 0 0)
			(layer "B.Fab")
			(effects
				(font
					(size 1.27 1.27)
				)
				(justify mirror)
			)
		)
		(duplicate_pad_numbers_are_jumpers no)
		(fp_line
			(start 0.69215 0.2921)
			(end 0.69215 -0.2921)
			(stroke
				(width 0.1524)
				(type default)
			)
			(layer "B.SilkS")
		)
		(fp_line
			(start 0.69215 -0.2921)
			(end -0.69215 -0.2921)
			(stroke
				(width 0.1524)
				(type default)
			)
			(layer "B.SilkS")
		)
		(fp_line
			(start -0.69215 0.2921)
			(end 0.69215 0.2921)
			(stroke
				(width 0.1524)
				(type default)
			)
			(layer "B.SilkS")
		)
		(fp_line
			(start -0.69215 -0.2921)
			(end -0.69215 0.2921)
			(stroke
				(width 0.1524)
				(type default)
			)
			(layer "B.SilkS")
		)
		(fp_line
			(start 0.51435 0.2794)
			(end 0.51435 -0.2794)
			(stroke
				(width 0.1)
				(type default)
			)
			(layer "B.Fab")
		)
		(fp_line
			(start 0.51435 -0.2794)
			(end -0.51435 -0.2794)
			(stroke
				(width 0.1)
				(type default)
			)
			(layer "B.Fab")
		)
		(fp_line
			(start -0.51435 0.2794)
			(end 0.51435 0.2794)
			(stroke
				(width 0.1)
				(type default)
			)
			(layer "B.Fab")
		)
		(fp_line
			(start -0.51435 -0.2794)
			(end -0.51435 0.2794)
			(stroke
				(width 0.1)
				(type default)
			)
			(layer "B.Fab")
		)
		(pad "1" smd circle
			(at 0.40005 0)
			(size 0 0)
			(layers "B.Cu" "B.Mask" "B.Paste")
			(net "PVCCA_AUX_PLD")
		)
		(pad "2" smd circle
			(at -0.40005 0)
			(size 0 0)
			(layers "B.Cu" "B.Mask" "B.Paste")
			(net "GND")
		)
		(zone
			(layer "B.Cu")
			(hatch none 0.5)
			(connect_pads
				(clearance 0)
			)
			(min_thickness 0.25)
			(keepout
				(tracks not_allowed)
				(vias allowed)
				(pads allowed)
				(copperpour not_allowed)
				(footprints allowed)
			)
			(placement
				(enabled no)
				(sheetname "")
			)
			(fill
				(thermal_gap 0.5)
				(thermal_bridge_width 0.5)
				(island_removal_mode 0)
			)
			(polygon
				(pts
					(xy 24.012144 -95.217742) (xy 24.103584 -95.275908) (xy 24.302974 -95.275908) (xy 24.393144 -95.217742)
					(xy 24.393144 -95.042482) (xy 24.302974 -94.984062) (xy 24.103584 -94.984062) (xy 24.012144 -95.042228)
				)
			)
		)
	)
	(footprint ""
		(layer "B.Cu")
		(at 56.861964 -70.046342)
		(property "Reference" "R783"
			(at 0 0 0)
			(layer "B.SilkS")
			(hide yes)
			(effects
				(font
					(size 1.27 1.27)
				)
				(justify mirror)
			)
		)
		(property "Value" ""
			(at 0 0 0)
			(layer "B.Fab")
			(effects
				(font
					(size 1.27 1.27)
				)
				(justify mirror)
			)
		)
		(duplicate_pad_numbers_are_jumpers no)
		(fp_line
			(start -0.7874 -0.4064)
			(end -0.7874 0.4064)
			(stroke
				(width 0.1524)
				(type default)
			)
			(layer "B.SilkS")
		)
		(fp_line
			(start -0.7874 0.4064)
			(end 0.7874 0.4064)
			(stroke
				(width 0.1524)
				(type default)
			)
			(layer "B.SilkS")
		)
		(fp_line
			(start 0.7874 -0.4064)
			(end -0.7874 -0.4064)
			(stroke
				(width 0.1524)
				(type default)
			)
			(layer "B.SilkS")
		)
		(fp_line
			(start 0.7874 0.4064)
			(end 0.7874 -0.4064)
			(stroke
				(width 0.1524)
				(type default)
			)
			(layer "B.SilkS")
		)
		(fp_line
			(start -0.67945 -0.3048)
			(end -0.67945 0.3048)
			(stroke
				(width 0.1)
				(type default)
			)
			(layer "B.Fab")
		)
		(fp_line
			(start -0.67945 0.3048)
			(end -0.120396 0.3048)
			(stroke
				(width 0.1)
				(type default)
			)
			(layer "B.Fab")
		)
		(fp_line
			(start -0.12065 -0.3048)
			(end -0.67945 -0.3048)
			(stroke
				(width 0.1)
				(type default)
			)
			(layer "B.Fab")
		)
		(fp_line
			(start -0.12065 -0.2794)
			(end -0.12065 -0.3048)
			(stroke
				(width 0.1)
				(type default)
			)
			(layer "B.Fab")
		)
		(fp_line
			(start -0.120396 0.2794)
			(end 0.12065 0.2794)
			(stroke
				(width 0.1)
				(type default)
			)
			(layer "B.Fab")
		)
		(fp_line
			(start -0.120396 0.3048)
			(end -0.120396 0.2794)
			(stroke
				(width 0.1)
				(type default)
			)
			(layer "B.Fab")
		)
		(fp_line
			(start 0.12065 -0.305054)
			(end 0.12065 -0.2794)
			(stroke
				(width 0.1)
				(type default)
			)
			(layer "B.Fab")
		)
		(fp_line
			(start 0.12065 -0.2794)
			(end -0.12065 -0.2794)
			(stroke
				(width 0.1)
				(type default)
			)
			(layer "B.Fab")
		)
		(fp_line
			(start 0.12065 0.2794)
			(end 0.12065 0.3048)
			(stroke
				(width 0.1)
				(type default)
			)
			(layer "B.Fab")
		)
		(fp_line
			(start 0.12065 0.3048)
			(end 0.67945 0.3048)
			(stroke
				(width 0.1)
				(type default)
			)
			(layer "B.Fab")
		)
		(fp_line
			(start 0.67945 -0.305054)
			(end 0.12065 -0.305054)
			(stroke
				(width 0.1)
				(type default)
			)
			(layer "B.Fab")
		)
		(fp_line
			(start 0.67945 0.3048)
			(end 0.67945 -0.305054)
			(stroke
				(width 0.1)
				(type default)
			)
			(layer "B.Fab")
		)
		(pad "1" smd circle
			(at 0.40005 0 180)
			(size 0 0)
			(layers "B.Cu" "B.Mask" "B.Paste")
			(net "P1V8_AUX")
		)
		(pad "2" smd circle
			(at -0.40005 0 180)
			(size 0 0)
			(layers "B.Cu" "B.Mask" "B.Paste")
			(net "ADCVREFEXT0")
		)
	)
	(footprint ""
		(layer "B.Cu")
		(at 82.933794 -49.907444 180)
		(property "Reference" "C1"
			(at 0 0 0)
			(layer "B.SilkS")
			(hide yes)
			(effects
				(font
					(size 1.27 1.27)
				)
				(justify mirror)
			)
		)
		(property "Value" ""
			(at 0 0 0)
			(layer "B.Fab")
			(effects
				(font
					(size 1.27 1.27)
				)
				(justify mirror)
			)
		)
		(duplicate_pad_numbers_are_jumpers no)
		(fp_line
			(start 1.2954 0.5842)
			(end 1.2954 -0.5842)
			(stroke
				(width 0.1524)
				(type default)
			)
			(layer "B.SilkS")
		)
		(fp_line
			(start 1.2954 -0.5842)
			(end -1.2954 -0.5842)
			(stroke
				(width 0.1524)
				(type default)
			)
			(layer "B.SilkS")
		)
		(fp_line
			(start 0 -0.5842)
			(end 0 0.5842)
			(stroke
				(width 0.1524)
				(type default)
			)
			(layer "B.SilkS")
		)
		(fp_line
			(start -1.2954 0.5842)
			(end 1.2954 0.5842)
			(stroke
				(width 0.1524)
				(type default)
			)
			(layer "B.SilkS")
		)
		(fp_line
			(start -1.2954 -0.5842)
			(end -1.2954 0.5842)
			(stroke
				(width 0.1524)
				(type default)
			)
			(layer "B.SilkS")
		)
		(fp_line
			(start 1.1938 0.4064)
			(end 1.1938 -0.4064)
			(stroke
				(width 0.1)
				(type default)
			)
			(layer "B.Fab")
		)
		(fp_line
			(start 1.1938 -0.4064)
			(end 0.8636 -0.4064)
			(stroke
				(width 0.1)
				(type default)
			)
			(layer "B.Fab")
		)
		(fp_line
			(start 0.8636 0.4572)
			(end 0.8636 0.4064)
			(stroke
				(width 0.1)
				(type default)
			)
			(layer "B.Fab")
		)
		(fp_line
			(start 0.8636 0.4064)
			(end 1.1938 0.4064)
			(stroke
				(width 0.1)
				(type default)
			)
			(layer "B.Fab")
		)
		(fp_line
			(start 0.8636 -0.4064)
			(end 0.8636 -0.4572)
			(stroke
				(width 0.1)
				(type default)
			)
			(layer "B.Fab")
		)
		(fp_line
			(start 0.8636 -0.4572)
			(end -0.8636 -0.4572)
			(stroke
				(width 0.1)
				(type default)
			)
			(layer "B.Fab")
		)
		(fp_line
			(start -0.8636 0.4572)
			(end 0.8636 0.4572)
			(stroke
				(width 0.1)
				(type default)
			)
			(layer "B.Fab")
		)
		(fp_line
			(start -0.8636 0.4064)
			(end -0.8636 0.4572)
			(stroke
				(width 0.1)
				(type default)
			)
			(layer "B.Fab")
		)
		(fp_line
			(start -0.8636 -0.4064)
			(end -1.1938 -0.4064)
			(stroke
				(width 0.1)
				(type default)
			)
			(layer "B.Fab")
		)
		(fp_line
			(start -0.8636 -0.4572)
			(end -0.8636 -0.4064)
			(stroke
				(width 0.1)
				(type default)
			)
			(layer "B.Fab")
		)
		(fp_line
			(start -1.1938 0.4064)
			(end -0.8636 0.4064)
			(stroke
				(width 0.1)
				(type default)
			)
			(layer "B.Fab")
		)
		(fp_line
			(start -1.1938 -0.4064)
			(end -1.1938 0.4064)
			(stroke
				(width 0.1)
				(type default)
			)
			(layer "B.Fab")
		)
		(pad "1" smd rect
			(at 0.7366 0 90)
			(size 0.7112 0.8128)
			(layers "B.Cu" "B.Mask" "B.Paste")
			(net "P1V2_AUX")
		)
		(pad "2" smd rect
			(at -0.7366 0 90)
			(size 0.7112 0.8128)
			(layers "B.Cu" "B.Mask" "B.Paste")
			(net "GND")
		)
	)
)
